(kicad_pcb
	(version 20260206)
	(generator "pcbnew")
	(generator_version "10.0")
	(general
		(thickness 1.6)
		(legacy_teardrops no)
	)
	(paper "A4")
	(title_block
		(title "12092022_DA0F0TMDCD0_F0T_Management_Board_D_brd_V3_OCP.brd")
		(comment 1 "Grand Teton / footprints 873-878 of 1440")
	)
	(layers
		(0 "F.Cu" signal "TOP")
		(4 "In1.Cu" signal "GND")
		(6 "In2.Cu" signal "IN1")
		(8 "In3.Cu" signal "GND1")
		(10 "In4.Cu" signal "IN2")
		(12 "In5.Cu" signal "VCC")
		(14 "In6.Cu" signal "VCC1")
		(16 "In7.Cu" signal "IN3")
		(18 "In8.Cu" signal "GND2")
		(20 "In9.Cu" signal "IN4")
		(22 "In10.Cu" signal "GND3")
		(2 "B.Cu" signal "BOTTOM")
		(9 "F.Adhes" user "F.Adhesive")
		(11 "B.Adhes" user "B.Adhesive")
		(13 "F.Paste" user "Package Geometry/Pastemask Top")
		(15 "B.Paste" user "Package Geometry/Pastemask Bottom")
		(5 "F.SilkS" user "Ref Des/Silkscreen Top")
		(7 "B.SilkS" user "Ref Des/Silkscreen Bottom")
		(1 "F.Mask" user "Board Geometry/Soldermask Top")
		(3 "B.Mask" user "Board Geometry/Soldermask Bottom")
		(17 "Dwgs.User" user "User.Drawings")
		(19 "Cmts.User" user "User.Comments")
		(21 "Eco1.User" user "User.Eco1")
		(23 "Eco2.User" user "User.Eco2")
		(25 "Edge.Cuts" user "Board Geometry/Outline")
		(27 "Margin" user)
		(31 "F.CrtYd" user "Package Geometry/Place Bound Top")
		(29 "B.CrtYd" user "Package Geometry/Place Bound Bottom")
		(35 "F.Fab" user "Ref Des/Assembly Top")
		(33 "B.Fab" user "Ref Des/Assembly Bottom")
	)
	(footprint ""
		(layer "B.Cu")
		(at 28.9306 -63.4746 180)
		(property "Reference" "R544"
			(at 0 0 0)
			(layer "B.SilkS")
			(hide yes)
			(effects
				(font
					(size 1.27 1.27)
				)
				(justify mirror)
			)
		)
		(property "Value" ""
			(at 0 0 0)
			(layer "B.Fab")
			(effects
				(font
					(size 1.27 1.27)
				)
				(justify mirror)
			)
		)
		(duplicate_pad_numbers_are_jumpers no)
		(fp_line
			(start 0.7874 0.4064)
			(end 0.7874 -0.4064)
			(stroke
				(width 0.1524)
				(type default)
			)
			(layer "B.SilkS")
		)
		(fp_line
			(start 0.7874 -0.4064)
			(end -0.7874 -0.4064)
			(stroke
				(width 0.1524)
				(type default)
			)
			(layer "B.SilkS")
		)
		(fp_line
			(start -0.7874 0.4064)
			(end 0.7874 0.4064)
			(stroke
				(width 0.1524)
				(type default)
			)
			(layer "B.SilkS")
		)
		(fp_line
			(start -0.7874 -0.4064)
			(end -0.7874 0.4064)
			(stroke
				(width 0.1524)
				(type default)
			)
			(layer "B.SilkS")
		)
		(fp_line
			(start 0.67945 0.3048)
			(end 0.67945 -0.305054)
			(stroke
				(width 0.1)
				(type default)
			)
			(layer "B.Fab")
		)
		(fp_line
			(start 0.67945 -0.305054)
			(end 0.12065 -0.305054)
			(stroke
				(width 0.1)
				(type default)
			)
			(layer "B.Fab")
		)
		(fp_line
			(start 0.12065 0.3048)
			(end 0.67945 0.3048)
			(stroke
				(width 0.1)
				(type default)
			)
			(layer "B.Fab")
		)
		(fp_line
			(start 0.12065 0.2794)
			(end 0.12065 0.3048)
			(stroke
				(width 0.1)
				(type default)
			)
			(layer "B.Fab")
		)
		(fp_line
			(start 0.12065 -0.2794)
			(end -0.12065 -0.2794)
			(stroke
				(width 0.1)
				(type default)
			)
			(layer "B.Fab")
		)
		(fp_line
			(start 0.12065 -0.305054)
			(end 0.12065 -0.2794)
			(stroke
				(width 0.1)
				(type default)
			)
			(layer "B.Fab")
		)
		(fp_line
			(start -0.120396 0.3048)
			(end -0.120396 0.2794)
			(stroke
				(width 0.1)
				(type default)
			)
			(layer "B.Fab")
		)
		(fp_line
			(start -0.120396 0.2794)
			(end 0.12065 0.2794)
			(stroke
				(width 0.1)
				(type default)
			)
			(layer "B.Fab")
		)
		(fp_line
			(start -0.12065 -0.2794)
			(end -0.12065 -0.3048)
			(stroke
				(width 0.1)
				(type default)
			)
			(layer "B.Fab")
		)
		(fp_line
			(start -0.12065 -0.3048)
			(end -0.67945 -0.3048)
			(stroke
				(width 0.1)
				(type default)
			)
			(layer "B.Fab")
		)
		(fp_line
			(start -0.67945 0.3048)
			(end -0.120396 0.3048)
			(stroke
				(width 0.1)
				(type default)
			)
			(layer "B.Fab")
		)
		(fp_line
			(start -0.67945 -0.3048)
			(end -0.67945 0.3048)
			(stroke
				(width 0.1)
				(type default)
			)
			(layer "B.Fab")
		)
		(pad "1" smd circle
			(at 0.40005 0)
			(size 0 0)
			(layers "B.Cu" "B.Mask" "B.Paste")
			(net "UART_SYS_DBG_TX")
		)
		(pad "2" smd circle
			(at -0.40005 0)
			(size 0 0)
			(layers "B.Cu" "B.Mask" "B.Paste")
			(net "UART_SYS_DBG_TX_R")
		)
	)
	(footprint ""
		(layer "B.Cu")
		(at 57.884822 -72.621648)
		(property "Reference" "R788"
			(at 0 0 0)
			(layer "B.SilkS")
			(hide yes)
			(effects
				(font
					(size 1.27 1.27)
				)
				(justify mirror)
			)
		)
		(property "Value" ""
			(at 0 0 0)
			(layer "B.Fab")
			(effects
				(font
					(size 1.27 1.27)
				)
				(justify mirror)
			)
		)
		(duplicate_pad_numbers_are_jumpers no)
		(fp_line
			(start -0.7874 -0.4064)
			(end -0.7874 0.4064)
			(stroke
				(width 0.1524)
				(type default)
			)
			(layer "B.SilkS")
		)
		(fp_line
			(start -0.7874 0.4064)
			(end 0.7874 0.4064)
			(stroke
				(width 0.1524)
				(type default)
			)
			(layer "B.SilkS")
		)
		(fp_line
			(start 0.7874 -0.4064)
			(end -0.7874 -0.4064)
			(stroke
				(width 0.1524)
				(type default)
			)
			(layer "B.SilkS")
		)
		(fp_line
			(start 0.7874 0.4064)
			(end 0.7874 -0.4064)
			(stroke
				(width 0.1524)
				(type default)
			)
			(layer "B.SilkS")
		)
		(fp_line
			(start -0.67945 -0.3048)
			(end -0.67945 0.3048)
			(stroke
				(width 0.1)
				(type default)
			)
			(layer "B.Fab")
		)
		(fp_line
			(start -0.67945 0.3048)
			(end -0.120396 0.3048)
			(stroke
				(width 0.1)
				(type default)
			)
			(layer "B.Fab")
		)
		(fp_line
			(start -0.12065 -0.3048)
			(end -0.67945 -0.3048)
			(stroke
				(width 0.1)
				(type default)
			)
			(layer "B.Fab")
		)
		(fp_line
			(start -0.12065 -0.2794)
			(end -0.12065 -0.3048)
			(stroke
				(width 0.1)
				(type default)
			)
			(layer "B.Fab")
		)
		(fp_line
			(start -0.120396 0.2794)
			(end 0.12065 0.2794)
			(stroke
				(width 0.1)
				(type default)
			)
			(layer "B.Fab")
		)
		(fp_line
			(start -0.120396 0.3048)
			(end -0.120396 0.2794)
			(stroke
				(width 0.1)
				(type default)
			)
			(layer "B.Fab")
		)
		(fp_line
			(start 0.12065 -0.305054)
			(end 0.12065 -0.2794)
			(stroke
				(width 0.1)
				(type default)
			)
			(layer "B.Fab")
		)
		(fp_line
			(start 0.12065 -0.2794)
			(end -0.12065 -0.2794)
			(stroke
				(width 0.1)
				(type default)
			)
			(layer "B.Fab")
		)
		(fp_line
			(start 0.12065 0.2794)
			(end 0.12065 0.3048)
			(stroke
				(width 0.1)
				(type default)
			)
			(layer "B.Fab")
		)
		(fp_line
			(start 0.12065 0.3048)
			(end 0.67945 0.3048)
			(stroke
				(width 0.1)
				(type default)
			)
			(layer "B.Fab")
		)
		(fp_line
			(start 0.67945 -0.305054)
			(end 0.12065 -0.305054)
			(stroke
				(width 0.1)
				(type default)
			)
			(layer "B.Fab")
		)
		(fp_line
			(start 0.67945 0.3048)
			(end 0.67945 -0.305054)
			(stroke
				(width 0.1)
				(type default)
			)
			(layer "B.Fab")
		)
		(pad "1" smd circle
			(at 0.40005 0 180)
			(size 0 0)
			(layers "B.Cu" "B.Mask" "B.Paste")
			(net "P5V_SENSOR")
		)
		(pad "2" smd circle
			(at -0.40005 0 180)
			(size 0 0)
			(layers "B.Cu" "B.Mask" "B.Paste")
			(net "GND")
		)
	)
	(footprint ""
		(layer "B.Cu")
		(at 51.55946 -61.852048 90)
		(property "Reference" "C135"
			(at 0 0 90)
			(layer "B.SilkS")
			(hide yes)
			(effects
				(font
					(size 1.27 1.27)
				)
				(justify mirror)
			)
		)
		(property "Value" ""
			(at 0 0 90)
			(layer "B.Fab")
			(effects
				(font
					(size 1.27 1.27)
				)
				(justify mirror)
			)
		)
		(duplicate_pad_numbers_are_jumpers no)
		(fp_line
			(start 0.7874 -0.4064)
			(end -0.7874 -0.4064)
			(stroke
				(width 0.1524)
				(type default)
			)
			(layer "B.SilkS")
		)
		(fp_line
			(start -0.7874 -0.4064)
			(end -0.7874 0.4064)
			(stroke
				(width 0.1524)
				(type default)
			)
			(layer "B.SilkS")
		)
		(fp_line
			(start 0.7874 0.4064)
			(end 0.7874 -0.4064)
			(stroke
				(width 0.1524)
				(type default)
			)
			(layer "B.SilkS")
		)
		(fp_line
			(start -0.7874 0.4064)
			(end 0.7874 0.4064)
			(stroke
				(width 0.1524)
				(type default)
			)
			(layer "B.SilkS")
		)
		(fp_line
			(start 0.67945 -0.305054)
			(end 0.12065 -0.305054)
			(stroke
				(width 0.1)
				(type default)
			)
			(layer "B.Fab")
		)
		(fp_line
			(start 0.12065 -0.305054)
			(end 0.12065 -0.2794)
			(stroke
				(width 0.1)
				(type default)
			)
			(layer "B.Fab")
		)
		(fp_line
			(start -0.12065 -0.3048)
			(end -0.67945 -0.3048)
			(stroke
				(width 0.1)
				(type default)
			)
			(layer "B.Fab")
		)
		(fp_line
			(start -0.67945 -0.3048)
			(end -0.67945 0.3048)
			(stroke
				(width 0.1)
				(type default)
			)
			(layer "B.Fab")
		)
		(fp_line
			(start 0.12065 -0.2794)
			(end -0.12065 -0.2794)
			(stroke
				(width 0.1)
				(type default)
			)
			(layer "B.Fab")
		)
		(fp_line
			(start -0.12065 -0.2794)
			(end -0.12065 -0.3048)
			(stroke
				(width 0.1)
				(type default)
			)
			(layer "B.Fab")
		)
		(fp_line
			(start 0.12065 0.2794)
			(end 0.12065 0.3048)
			(stroke
				(width 0.1)
				(type default)
			)
			(layer "B.Fab")
		)
		(fp_line
			(start -0.120396 0.2794)
			(end 0.12065 0.2794)
			(stroke
				(width 0.1)
				(type default)
			)
			(layer "B.Fab")
		)
		(fp_line
			(start 0.67945 0.3048)
			(end 0.67945 -0.305054)
			(stroke
				(width 0.1)
				(type default)
			)
			(layer "B.Fab")
		)
		(fp_line
			(start 0.12065 0.3048)
			(end 0.67945 0.3048)
			(stroke
				(width 0.1)
				(type default)
			)
			(layer "B.Fab")
		)
		(fp_line
			(start -0.120396 0.3048)
			(end -0.120396 0.2794)
			(stroke
				(width 0.1)
				(type default)
			)
			(layer "B.Fab")
		)
		(fp_line
			(start -0.67945 0.3048)
			(end -0.120396 0.3048)
			(stroke
				(width 0.1)
				(type default)
			)
			(layer "B.Fab")
		)
		(pad "1" smd circle
			(at 0.40005 0 270)
			(size 0 0)
			(layers "B.Cu" "B.Mask" "B.Paste")
			(net "GND")
		)
		(pad "2" smd circle
			(at -0.40005 0 270)
			(size 0 0)
			(layers "B.Cu" "B.Mask" "B.Paste")
			(net "A_BMC_ADCVREFP1")
		)
	)
	(footprint ""
		(layer "B.Cu")
		(at 62.103 -54.61 -90)
		(property "Reference" "C87"
			(at 0 0 90)
			(layer "B.SilkS")
			(hide yes)
			(effects
				(font
					(size 1.27 1.27)
				)
				(justify mirror)
			)
		)
		(property "Value" ""
			(at 0 0 90)
			(layer "B.Fab")
			(effects
				(font
					(size 1.27 1.27)
				)
				(justify mirror)
			)
		)
		(duplicate_pad_numbers_are_jumpers no)
		(fp_line
			(start -0.7874 0.4064)
			(end 0.7874 0.4064)
			(stroke
				(width 0.1524)
				(type default)
			)
			(layer "B.SilkS")
		)
		(fp_line
			(start 0.7874 0.4064)
			(end 0.7874 -0.4064)
			(stroke
				(width 0.1524)
				(type default)
			)
			(layer "B.SilkS")
		)
		(fp_line
			(start -0.7874 -0.4064)
			(end -0.7874 0.4064)
			(stroke
				(width 0.1524)
				(type default)
			)
			(layer "B.SilkS")
		)
		(fp_line
			(start 0.7874 -0.4064)
			(end -0.7874 -0.4064)
			(stroke
				(width 0.1524)
				(type default)
			)
			(layer "B.SilkS")
		)
		(fp_line
			(start -0.67945 0.3048)
			(end -0.120396 0.3048)
			(stroke
				(width 0.1)
				(type default)
			)
			(layer "B.Fab")
		)
		(fp_line
			(start -0.120396 0.3048)
			(end -0.120396 0.2794)
			(stroke
				(width 0.1)
				(type default)
			)
			(layer "B.Fab")
		)
		(fp_line
			(start 0.12065 0.3048)
			(end 0.67945 0.3048)
			(stroke
				(width 0.1)
				(type default)
			)
			(layer "B.Fab")
		)
		(fp_line
			(start 0.67945 0.3048)
			(end 0.67945 -0.305054)
			(stroke
				(width 0.1)
				(type default)
			)
			(layer "B.Fab")
		)
		(fp_line
			(start -0.120396 0.2794)
			(end 0.12065 0.2794)
			(stroke
				(width 0.1)
				(type default)
			)
			(layer "B.Fab")
		)
		(fp_line
			(start 0.12065 0.2794)
			(end 0.12065 0.3048)
			(stroke
				(width 0.1)
				(type default)
			)
			(layer "B.Fab")
		)
		(fp_line
			(start -0.12065 -0.2794)
			(end -0.12065 -0.3048)
			(stroke
				(width 0.1)
				(type default)
			)
			(layer "B.Fab")
		)
		(fp_line
			(start 0.12065 -0.2794)
			(end -0.12065 -0.2794)
			(stroke
				(width 0.1)
				(type default)
			)
			(layer "B.Fab")
		)
		(fp_line
			(start -0.67945 -0.3048)
			(end -0.67945 0.3048)
			(stroke
				(width 0.1)
				(type default)
			)
			(layer "B.Fab")
		)
		(fp_line
			(start -0.12065 -0.3048)
			(end -0.67945 -0.3048)
			(stroke
				(width 0.1)
				(type default)
			)
			(layer "B.Fab")
		)
		(fp_line
			(start 0.12065 -0.305054)
			(end 0.12065 -0.2794)
			(stroke
				(width 0.1)
				(type default)
			)
			(layer "B.Fab")
		)
		(fp_line
			(start 0.67945 -0.305054)
			(end 0.12065 -0.305054)
			(stroke
				(width 0.1)
				(type default)
			)
			(layer "B.Fab")
		)
		(pad "1" smd circle
			(at 0.40005 0 90)
			(size 0 0)
			(layers "B.Cu" "B.Mask" "B.Paste")
			(net "P1V8_AUX")
		)
		(pad "2" smd circle
			(at -0.40005 0 90)
			(size 0 0)
			(layers "B.Cu" "B.Mask" "B.Paste")
			(net "GND")
		)
	)
	(footprint ""
		(layer "B.Cu")
		(at 56.710326 -60.8076 90)
		(property "Reference" "R801"
			(at 0 0 90)
			(layer "B.SilkS")
			(hide yes)
			(effects
				(font
					(size 1.27 1.27)
				)
				(justify mirror)
			)
		)
		(property "Value" ""
			(at 0 0 90)
			(layer "B.Fab")
			(effects
				(font
					(size 1.27 1.27)
				)
				(justify mirror)
			)
		)
		(duplicate_pad_numbers_are_jumpers no)
		(fp_line
			(start 0.7874 -0.4064)
			(end -0.7874 -0.4064)
			(stroke
				(width 0.1524)
				(type default)
			)
			(layer "B.SilkS")
		)
		(fp_line
			(start -0.7874 -0.4064)
			(end -0.7874 0.4064)
			(stroke
				(width 0.1524)
				(type default)
			)
			(layer "B.SilkS")
		)
		(fp_line
			(start 0.7874 0.4064)
			(end 0.7874 -0.4064)
			(stroke
				(width 0.1524)
				(type default)
			)
			(layer "B.SilkS")
		)
		(fp_line
			(start -0.7874 0.4064)
			(end 0.7874 0.4064)
			(stroke
				(width 0.1524)
				(type default)
			)
			(layer "B.SilkS")
		)
		(fp_line
			(start 0.67945 -0.305054)
			(end 0.12065 -0.305054)
			(stroke
				(width 0.1)
				(type default)
			)
			(layer "B.Fab")
		)
		(fp_line
			(start 0.12065 -0.305054)
			(end 0.12065 -0.2794)
			(stroke
				(width 0.1)
				(type default)
			)
			(layer "B.Fab")
		)
		(fp_line
			(start -0.12065 -0.3048)
			(end -0.67945 -0.3048)
			(stroke
				(width 0.1)
				(type default)
			)
			(layer "B.Fab")
		)
		(fp_line
			(start -0.67945 -0.3048)
			(end -0.67945 0.3048)
			(stroke
				(width 0.1)
				(type default)
			)
			(layer "B.Fab")
		)
		(fp_line
			(start 0.12065 -0.2794)
			(end -0.12065 -0.2794)
			(stroke
				(width 0.1)
				(type default)
			)
			(layer "B.Fab")
		)
		(fp_line
			(start -0.12065 -0.2794)
			(end -0.12065 -0.3048)
			(stroke
				(width 0.1)
				(type default)
			)
			(layer "B.Fab")
		)
		(fp_line
			(start 0.12065 0.2794)
			(end 0.12065 0.3048)
			(stroke
				(width 0.1)
				(type default)
			)
			(layer "B.Fab")
		)
		(fp_line
			(start -0.120396 0.2794)
			(end 0.12065 0.2794)
			(stroke
				(width 0.1)
				(type default)
			)
			(layer "B.Fab")
		)
		(fp_line
			(start 0.67945 0.3048)
			(end 0.67945 -0.305054)
			(stroke
				(width 0.1)
				(type default)
			)
			(layer "B.Fab")
		)
		(fp_line
			(start 0.12065 0.3048)
			(end 0.67945 0.3048)
			(stroke
				(width 0.1)
				(type default)
			)
			(layer "B.Fab")
		)
		(fp_line
			(start -0.120396 0.3048)
			(end -0.120396 0.2794)
			(stroke
				(width 0.1)
				(type default)
			)
			(layer "B.Fab")
		)
		(fp_line
			(start -0.67945 0.3048)
			(end -0.120396 0.3048)
			(stroke
				(width 0.1)
				(type default)
			)
			(layer "B.Fab")
		)
		(pad "1" smd circle
			(at 0.40005 0 270)
			(size 0 0)
			(layers "B.Cu" "B.Mask" "B.Paste")
			(net "SPI_BMC_BOOT_CS0_R_N")
		)
		(pad "2" smd circle
			(at -0.40005 0 270)
			(size 0 0)
			(layers "B.Cu" "B.Mask" "B.Paste")
			(net "SPI_BMC_BOOT_CS0_R1_N")
		)
	)
	(footprint ""
		(layer "B.Cu")
		(at 65.0494 -28.3464 90)
		(property "Reference" "R204"
			(at 0 0 90)
			(layer "B.SilkS")
			(hide yes)
			(effects
				(font
					(size 1.27 1.27)
				)
				(justify mirror)
			)
		)
		(property "Value" ""
			(at 0 0 90)
			(layer "B.Fab")
			(effects
				(font
					(size 1.27 1.27)
				)
				(justify mirror)
			)
		)
		(duplicate_pad_numbers_are_jumpers no)
		(fp_line
			(start 0.7874 -0.4064)
			(end -0.7874 -0.4064)
			(stroke
				(width 0.1524)
				(type default)
			)
			(layer "B.SilkS")
		)
		(fp_line
			(start -0.7874 -0.4064)
			(end -0.7874 0.4064)
			(stroke
				(width 0.1524)
				(type default)
			)
			(layer "B.SilkS")
		)
		(fp_line
			(start 0.7874 0.4064)
			(end 0.7874 -0.4064)
			(stroke
				(width 0.1524)
				(type default)
			)
			(layer "B.SilkS")
		)
		(fp_line
			(start -0.7874 0.4064)
			(end 0.7874 0.4064)
			(stroke
				(width 0.1524)
				(type default)
			)
			(layer "B.SilkS")
		)
		(fp_line
			(start 0.67945 -0.305054)
			(end 0.12065 -0.305054)
			(stroke
				(width 0.1)
				(type default)
			)
			(layer "B.Fab")
		)
		(fp_line
			(start 0.12065 -0.305054)
			(end 0.12065 -0.2794)
			(stroke
				(width 0.1)
				(type default)
			)
			(layer "B.Fab")
		)
		(fp_line
			(start -0.12065 -0.3048)
			(end -0.67945 -0.3048)
			(stroke
				(width 0.1)
				(type default)
			)
			(layer "B.Fab")
		)
		(fp_line
			(start -0.67945 -0.3048)
			(end -0.67945 0.3048)
			(stroke
				(width 0.1)
				(type default)
			)
			(layer "B.Fab")
		)
		(fp_line
			(start 0.12065 -0.2794)
			(end -0.12065 -0.2794)
			(stroke
				(width 0.1)
				(type default)
			)
			(layer "B.Fab")
		)
		(fp_line
			(start -0.12065 -0.2794)
			(end -0.12065 -0.3048)
			(stroke
				(width 0.1)
				(type default)
			)
			(layer "B.Fab")
		)
		(fp_line
			(start 0.12065 0.2794)
			(end 0.12065 0.3048)
			(stroke
				(width 0.1)
				(type default)
			)
			(layer "B.Fab")
		)
		(fp_line
			(start -0.120396 0.2794)
			(end 0.12065 0.2794)
			(stroke
				(width 0.1)
				(type default)
			)
			(layer "B.Fab")
		)
		(fp_line
			(start 0.67945 0.3048)
			(end 0.67945 -0.305054)
			(stroke
				(width 0.1)
				(type default)
			)
			(layer "B.Fab")
		)
		(fp_line
			(start 0.12065 0.3048)
			(end 0.67945 0.3048)
			(stroke
				(width 0.1)
				(type default)
			)
			(layer "B.Fab")
		)
		(fp_line
			(start -0.120396 0.3048)
			(end -0.120396 0.2794)
			(stroke
				(width 0.1)
				(type default)
			)
			(layer "B.Fab")
		)
		(fp_line
			(start -0.67945 0.3048)
			(end -0.120396 0.3048)
			(stroke
				(width 0.1)
				(type default)
			)
			(layer "B.Fab")
		)
		(pad "1" smd circle
			(at 0.40005 0 270)
			(size 0 0)
			(layers "B.Cu" "B.Mask" "B.Paste")
			(net "P3V3_RGM")
		)
		(pad "2" smd circle
			(at -0.40005 0 270)
			(size 0 0)
			(layers "B.Cu" "B.Mask" "B.Paste")
			(net "JTAG_SCM_TDI")
		)
	)
)
